(kicad_pcb
	(version 20260206)
	(generator "pcbnew")
	(generator_version "10.0")
	(general
		(thickness 1.6)
		(legacy_teardrops no)
	)
	(paper "A4")
	(title_block
		(title "Wiwynn_Tioga_Pass_MB.brd")
		(comment 1 "Tioga Pass / footprints 1887-1892 of 4770")
	)
	(layers
		(0 "F.Cu" signal "TOP")
		(4 "In1.Cu" signal "L2GND")
		(6 "In2.Cu" signal "L3")
		(8 "In3.Cu" signal "L4GND")
		(10 "In4.Cu" signal "L5")
		(12 "In5.Cu" signal "L6GND")
		(14 "In6.Cu" signal "L7VCC")
		(16 "In7.Cu" signal "L8VCC")
		(18 "In8.Cu" signal "L9GND")
		(20 "In9.Cu" signal "L10")
		(22 "In10.Cu" signal "L11GND")
		(24 "In11.Cu" signal "L12")
		(26 "In12.Cu" signal "L13GND")
		(2 "B.Cu" signal "BOTTOM")
		(9 "F.Adhes" user "F.Adhesive")
		(11 "B.Adhes" user "B.Adhesive")
		(13 "F.Paste" user "Package Geometry/Pastemask Top")
		(15 "B.Paste" user "Package Geometry/Pastemask Bottom")
		(5 "F.SilkS" user "Ref Des/Silkscreen Top")
		(7 "B.SilkS" user "Ref Des/Silkscreen Bottom")
		(1 "F.Mask" user "Board Geometry/Soldermask Top")
		(3 "B.Mask" user "Board Geometry/Soldermask Bottom")
		(17 "Dwgs.User" user "User.Drawings")
		(19 "Cmts.User" user "User.Comments")
		(21 "Eco1.User" user "User.Eco1")
		(23 "Eco2.User" user "User.Eco2")
		(25 "Edge.Cuts" user "Board Geometry/Outline")
		(27 "Margin" user)
		(31 "F.CrtYd" user "Package Geometry/Place Bound Top")
		(29 "B.CrtYd" user "Package Geometry/Place Bound Bottom")
		(35 "F.Fab" user "Ref Des/Assembly Top")
		(33 "B.Fab" user "Ref Des/Assembly Bottom")
	)
	(footprint ""
		(layer "F.Cu")
		(at 433.3494 -31.7373 180)
		(property "Reference" "R25W117"
			(at -0.8382 -0.67818 180)
			(unlocked yes)
			(layer "F.SilkS")
			(effects
				(font
					(size 0.4064 0.254)
					(thickness 0.1524)
				)
				(justify left)
			)
		)
		(property "Value" ""
			(at 0 0 180)
			(layer "F.Fab")
			(effects
				(font
					(size 1.27 1.27)
				)
			)
		)
		(duplicate_pad_numbers_are_jumpers no)
		(fp_poly
			(pts
				(xy -0.2794 -0.1016) (xy 0.2794 -0.1016) (xy 0.2794 0.9906) (xy -0.2794 0.9906)
			)
			(stroke
				(width 0)
				(type default)
			)
			(fill no)
			(layer "F.CrtYd")
		)
		(fp_line
			(start 0.2794 0.9906)
			(end 0.2794 -0.1016)
			(stroke
				(width 0.1)
				(type default)
			)
			(layer "F.Fab")
		)
		(fp_line
			(start 0.2794 -0.1016)
			(end -0.2794 -0.1016)
			(stroke
				(width 0.1)
				(type default)
			)
			(layer "F.Fab")
		)
		(fp_line
			(start -0.2794 0.9906)
			(end 0.2794 0.9906)
			(stroke
				(width 0.1)
				(type default)
			)
			(layer "F.Fab")
		)
		(fp_line
			(start -0.2794 -0.1016)
			(end -0.2794 0.9906)
			(stroke
				(width 0.1)
				(type default)
			)
			(layer "F.Fab")
		)
		(pad "1" smd rect
			(at 0 0 180)
			(size 0.508 0.508)
			(layers "F.Cu" "F.Mask" "F.Paste")
			(net "BMC_ZQ")
		)
		(pad "2" smd rect
			(at 0 0.889 180)
			(size 0.508 0.508)
			(layers "F.Cu" "F.Mask" "F.Paste")
			(net "GND")
		)
		(zone
			(layer "F.Cu")
			(hatch none 0.5)
			(connect_pads
				(clearance 0)
			)
			(min_thickness 0.25)
			(keepout
				(tracks not_allowed)
				(vias allowed)
				(pads allowed)
				(copperpour not_allowed)
				(footprints allowed)
			)
			(placement
				(enabled no)
				(sheetname "")
			)
			(fill
				(thermal_gap 0.5)
				(thermal_bridge_width 0.5)
				(island_removal_mode 0)
			)
			(polygon
				(pts
					(xy 433.6034 -32.3723) (xy 433.0954 -32.3723) (xy 433.0954 -31.9913) (xy 433.6034 -31.9913)
				)
			)
		)
		(zone
			(layer "F.Cu")
			(hatch none 0.5)
			(connect_pads
				(clearance 0)
			)
			(min_thickness 0.25)
			(keepout
				(tracks allowed)
				(vias not_allowed)
				(pads allowed)
				(copperpour not_allowed)
				(footprints allowed)
			)
			(placement
				(enabled no)
				(sheetname "")
			)
			(fill
				(thermal_gap 0.5)
				(thermal_bridge_width 0.5)
				(island_removal_mode 0)
			)
			(polygon
				(pts
					(xy 433.6034 -31.9913) (xy 433.0954 -31.9913) (xy 433.0954 -32.3723) (xy 433.6034 -32.3723)
				)
			)
		)
	)
	(footprint ""
		(layer "F.Cu")
		(at 154.305 -28.8798 90)
		(property "Reference" "R3F4"
			(at 0 0 90)
			(layer "F.SilkS")
			(hide yes)
			(effects
				(font
					(size 1.27 1.27)
				)
			)
		)
		(property "Value" ""
			(at 0 0 90)
			(layer "F.Fab")
			(effects
				(font
					(size 1.27 1.27)
				)
			)
		)
		(duplicate_pad_numbers_are_jumpers no)
		(fp_poly
			(pts
				(xy -0.2794 -0.1016) (xy 0.2794 -0.1016) (xy 0.2794 0.9906) (xy -0.2794 0.9906)
			)
			(stroke
				(width 0)
				(type default)
			)
			(fill no)
			(layer "F.CrtYd")
		)
		(fp_line
			(start 0.2794 -0.1016)
			(end -0.2794 -0.1016)
			(stroke
				(width 0.1)
				(type default)
			)
			(layer "F.Fab")
		)
		(fp_line
			(start -0.2794 -0.1016)
			(end -0.2794 0.9906)
			(stroke
				(width 0.1)
				(type default)
			)
			(layer "F.Fab")
		)
		(fp_line
			(start 0.2794 0.9906)
			(end 0.2794 -0.1016)
			(stroke
				(width 0.1)
				(type default)
			)
			(layer "F.Fab")
		)
		(fp_line
			(start -0.2794 0.9906)
			(end 0.2794 0.9906)
			(stroke
				(width 0.1)
				(type default)
			)
			(layer "F.Fab")
		)
		(pad "1" smd rect
			(at 0 0 90)
			(size 0.508 0.508)
			(layers "F.Cu" "F.Mask" "F.Paste")
			(net "CLK_156M_OSC_BRD_CPU1_DP")
		)
		(pad "2" smd rect
			(at 0 0.889 90)
			(size 0.508 0.508)
			(layers "F.Cu" "F.Mask" "F.Paste")
			(net "CLK_156M_OSC_CPU1_HFI_DP")
		)
		(zone
			(layer "F.Cu")
			(hatch none 0.5)
			(connect_pads
				(clearance 0)
			)
			(min_thickness 0.25)
			(keepout
				(tracks allowed)
				(vias not_allowed)
				(pads allowed)
				(copperpour not_allowed)
				(footprints allowed)
			)
			(placement
				(enabled no)
				(sheetname "")
			)
			(fill
				(thermal_gap 0.5)
				(thermal_bridge_width 0.5)
				(island_removal_mode 0)
			)
			(polygon
				(pts
					(xy 154.559 -28.6258) (xy 154.559 -29.1338) (xy 154.94 -29.1338) (xy 154.94 -28.6258)
				)
			)
		)
		(zone
			(layer "F.Cu")
			(hatch none 0.5)
			(connect_pads
				(clearance 0)
			)
			(min_thickness 0.25)
			(keepout
				(tracks not_allowed)
				(vias allowed)
				(pads allowed)
				(copperpour not_allowed)
				(footprints allowed)
			)
			(placement
				(enabled no)
				(sheetname "")
			)
			(fill
				(thermal_gap 0.5)
				(thermal_bridge_width 0.5)
				(island_removal_mode 0)
			)
			(polygon
				(pts
					(xy 154.94 -28.6258) (xy 154.94 -29.1338) (xy 154.559 -29.1338) (xy 154.559 -28.6258)
				)
			)
		)
	)
	(footprint ""
		(layer "F.Cu")
		(at 342.4428 -126.746 90)
		(property "Reference" "C7B14"
			(at 0 0 90)
			(layer "F.SilkS")
			(hide yes)
			(effects
				(font
					(size 1.27 1.27)
				)
			)
		)
		(property "Value" ""
			(at 0 0 90)
			(layer "F.Fab")
			(effects
				(font
					(size 1.27 1.27)
				)
			)
		)
		(duplicate_pad_numbers_are_jumpers no)
		(fp_poly
			(pts
				(xy 0.3048 -0.1016) (xy 0.3048 0.9906) (xy -0.3048 0.9906) (xy -0.3048 -0.1016)
			)
			(stroke
				(width 0)
				(type default)
			)
			(fill no)
			(layer "F.CrtYd")
		)
		(fp_line
			(start 0.3048 -0.1016)
			(end -0.3048 -0.1016)
			(stroke
				(width 0.1)
				(type default)
			)
			(layer "F.Fab")
		)
		(fp_line
			(start -0.3048 -0.1016)
			(end -0.3048 0.9906)
			(stroke
				(width 0.1)
				(type default)
			)
			(layer "F.Fab")
		)
		(fp_line
			(start 0.3048 0.9906)
			(end 0.3048 -0.1016)
			(stroke
				(width 0.1)
				(type default)
			)
			(layer "F.Fab")
		)
		(fp_line
			(start -0.3048 0.9906)
			(end 0.3048 0.9906)
			(stroke
				(width 0.1)
				(type default)
			)
			(layer "F.Fab")
		)
		(pad "1" smd rect
			(at 0 0 90)
			(size 0.508 0.508)
			(layers "F.Cu" "F.Mask" "F.Paste")
			(net "VR_COMP_RC_PVPP_DEF")
		)
		(pad "2" smd rect
			(at 0 0.889 90)
			(size 0.508 0.508)
			(layers "F.Cu" "F.Mask" "F.Paste")
			(net "VR_COMP_PVPP_DEF_3")
		)
		(zone
			(layer "F.Cu")
			(hatch none 0.5)
			(connect_pads
				(clearance 0)
			)
			(min_thickness 0.25)
			(keepout
				(tracks allowed)
				(vias not_allowed)
				(pads allowed)
				(copperpour not_allowed)
				(footprints allowed)
			)
			(placement
				(enabled no)
				(sheetname "")
			)
			(fill
				(thermal_gap 0.5)
				(thermal_bridge_width 0.5)
				(island_removal_mode 0)
			)
			(polygon
				(pts
					(xy 342.6968 -126.492) (xy 342.6968 -127) (xy 343.0778 -127) (xy 343.0778 -126.492)
				)
			)
		)
		(zone
			(layer "F.Cu")
			(hatch none 0.5)
			(connect_pads
				(clearance 0)
			)
			(min_thickness 0.25)
			(keepout
				(tracks not_allowed)
				(vias allowed)
				(pads allowed)
				(copperpour not_allowed)
				(footprints allowed)
			)
			(placement
				(enabled no)
				(sheetname "")
			)
			(fill
				(thermal_gap 0.5)
				(thermal_bridge_width 0.5)
				(island_removal_mode 0)
			)
			(polygon
				(pts
					(xy 343.0778 -126.492) (xy 343.0778 -127) (xy 342.6968 -127) (xy 342.6968 -126.492)
				)
			)
		)
	)
	(footprint ""
		(layer "F.Cu")
		(at 205.025498 -97.454974)
		(property "Reference" "L4C2"
			(at 3.378708 -4.251706 0)
			(unlocked yes)
			(layer "F.SilkS")
			(effects
				(font
					(size 0.4064 0.254)
					(thickness 0.1524)
				)
			)
		)
		(property "Value" ""
			(at 0 0 0)
			(layer "F.Fab")
			(effects
				(font
					(size 1.27 1.27)
				)
			)
		)
		(duplicate_pad_numbers_are_jumpers no)
		(fp_line
			(start -1.1303 -3.199892)
			(end 8.3693 -3.199892)
			(stroke
				(width 0.1524)
				(type default)
			)
			(layer "F.SilkS")
		)
		(fp_line
			(start -1.1303 -1.6637)
			(end -1.1303 -3.199892)
			(stroke
				(width 0.1524)
				(type default)
			)
			(layer "F.SilkS")
		)
		(fp_line
			(start -1.1303 3.199892)
			(end -1.1303 1.6637)
			(stroke
				(width 0.1524)
				(type default)
			)
			(layer "F.SilkS")
		)
		(fp_line
			(start 8.3693 -3.199892)
			(end 8.3693 -1.6637)
			(stroke
				(width 0.1524)
				(type default)
			)
			(layer "F.SilkS")
		)
		(fp_line
			(start 8.3693 1.6637)
			(end 8.3693 3.199892)
			(stroke
				(width 0.1524)
				(type default)
			)
			(layer "F.SilkS")
		)
		(fp_line
			(start 8.3693 3.199892)
			(end -1.1303 3.199892)
			(stroke
				(width 0.1524)
				(type default)
			)
			(layer "F.SilkS")
		)
		(fp_rect
			(start -1.1303 3.199892)
			(end 8.3693 -3.199892)
			(stroke
				(width 0)
				(type default)
			)
			(fill no)
			(layer "F.CrtYd")
		)
		(fp_line
			(start -1.1303 -3.199892)
			(end 8.3693 -3.199892)
			(stroke
				(width 0.1)
				(type default)
			)
			(layer "F.Fab")
		)
		(fp_line
			(start -1.1303 3.199892)
			(end -1.1303 -3.199892)
			(stroke
				(width 0.1)
				(type default)
			)
			(layer "F.Fab")
		)
		(fp_line
			(start 8.3693 -3.199892)
			(end 8.3693 3.199892)
			(stroke
				(width 0.1)
				(type default)
			)
			(layer "F.Fab")
		)
		(fp_line
			(start 8.3693 3.199892)
			(end -1.1303 3.199892)
			(stroke
				(width 0.1)
				(type default)
			)
			(layer "F.Fab")
		)
		(pad "1" smd rect
			(at 0 0)
			(size 3.683 2.667)
			(layers "F.Cu" "F.Mask" "F.Paste")
			(net "VR_PVSA_CPU0_PHASE_SW")
		)
		(pad "2" smd rect
			(at 7.239 0)
			(size 3.683 2.667)
			(layers "F.Cu" "F.Mask" "F.Paste")
			(net "PVSA_CPU0")
		)
	)
	(footprint ""
		(layer "F.Cu")
		(at 269.559532 -12.954 90)
		(property "Reference" "C5G6"
			(at 1.848866 0.752348 90)
			(unlocked yes)
			(layer "F.SilkS")
			(effects
				(font
					(size 1.27 0.9652)
					(thickness 0.1524)
				)
			)
		)
		(property "Value" ""
			(at 0 0 90)
			(layer "F.Fab")
			(effects
				(font
					(size 1.27 1.27)
				)
			)
		)
		(duplicate_pad_numbers_are_jumpers no)
		(fp_rect
			(start -0.500126 1.598422)
			(end 0.500126 -0.201422)
			(stroke
				(width 0)
				(type default)
			)
			(fill no)
			(layer "F.CrtYd")
		)
		(fp_line
			(start 0.500126 -0.201422)
			(end 0.500126 1.598422)
			(stroke
				(width 0.1)
				(type default)
			)
			(layer "F.Fab")
		)
		(fp_line
			(start -0.500126 -0.201422)
			(end 0.500126 -0.201422)
			(stroke
				(width 0.1)
				(type default)
			)
			(layer "F.Fab")
		)
		(fp_line
			(start 0.500126 1.598422)
			(end -0.500126 1.598422)
			(stroke
				(width 0.1)
				(type default)
			)
			(layer "F.Fab")
		)
		(fp_line
			(start -0.500126 1.598422)
			(end -0.500126 -0.201422)
			(stroke
				(width 0.1)
				(type default)
			)
			(layer "F.Fab")
		)
		(pad "1" smd rect
			(at 0 0)
			(size 0.889 0.9906)
			(layers "F.Cu" "F.Mask" "F.Paste")
			(net "PVDDQ_ABC")
		)
		(pad "2" smd rect
			(at 0 1.397)
			(size 0.889 0.9906)
			(layers "F.Cu" "F.Mask" "F.Paste")
			(net "GND")
		)
		(zone
			(layer "F.Cu")
			(hatch none 0.5)
			(connect_pads
				(clearance 0)
			)
			(min_thickness 0.25)
			(keepout
				(tracks not_allowed)
				(vias allowed)
				(pads allowed)
				(copperpour not_allowed)
				(footprints allowed)
			)
			(placement
				(enabled no)
				(sheetname "")
			)
			(fill
				(thermal_gap 0.5)
				(thermal_bridge_width 0.5)
				(island_removal_mode 0)
			)
			(polygon
				(pts
					(xy 270.512032 -12.4587) (xy 270.512032 -13.4493) (xy 270.004032 -13.4493) (xy 270.004032 -12.4587)
				)
			)
		)
		(zone
			(layer "F.Cu")
			(hatch none 0.5)
			(connect_pads
				(clearance 0)
			)
			(min_thickness 0.25)
			(keepout
				(tracks allowed)
				(vias not_allowed)
				(pads allowed)
				(copperpour not_allowed)
				(footprints allowed)
			)
			(placement
				(enabled no)
				(sheetname "")
			)
			(fill
				(thermal_gap 0.5)
				(thermal_bridge_width 0.5)
				(island_removal_mode 0)
			)
			(polygon
				(pts
					(xy 270.512032 -12.4587) (xy 270.512032 -13.4493) (xy 270.004032 -13.4493) (xy 270.004032 -12.4587)
				)
			)
		)
	)
	(footprint ""
		(layer "F.Cu")
		(at 155.702 -140.0048 90)
		(property "Reference" "C3A8"
			(at 0 0 90)
			(layer "F.SilkS")
			(hide yes)
			(effects
				(font
					(size 1.27 1.27)
				)
			)
		)
		(property "Value" ""
			(at 0 0 90)
			(layer "F.Fab")
			(effects
				(font
					(size 1.27 1.27)
				)
			)
		)
		(duplicate_pad_numbers_are_jumpers no)
		(fp_rect
			(start -0.4953 1.6002)
			(end 0.4953 -0.2032)
			(stroke
				(width 0)
				(type default)
			)
			(fill no)
			(layer "F.CrtYd")
		)
		(fp_line
			(start 0.4953 -0.2032)
			(end 0.4953 1.6002)
			(stroke
				(width 0.1)
				(type default)
			)
			(layer "F.Fab")
		)
		(fp_line
			(start -0.4953 -0.2032)
			(end 0.4953 -0.2032)
			(stroke
				(width 0.1)
				(type default)
			)
			(layer "F.Fab")
		)
		(fp_line
			(start 0.4953 1.6002)
			(end -0.4953 1.6002)
			(stroke
				(width 0.1)
				(type default)
			)
			(layer "F.Fab")
		)
		(fp_line
			(start -0.4953 1.6002)
			(end -0.4953 -0.2032)
			(stroke
				(width 0.1)
				(type default)
			)
			(layer "F.Fab")
		)
		(pad "1" smd rect
			(at 0 0 90)
			(size 0.762 0.889)
			(layers "F.Cu" "F.Mask" "F.Paste")
			(net "PVPP_KLM")
		)
		(pad "2" smd rect
			(at 0 1.397 90)
			(size 0.762 0.889)
			(layers "F.Cu" "F.Mask" "F.Paste")
			(net "GND")
		)
		(zone
			(layer "F.Cu")
			(hatch none 0.5)
			(connect_pads
				(clearance 0)
			)
			(min_thickness 0.25)
			(keepout
				(tracks not_allowed)
				(vias allowed)
				(pads allowed)
				(copperpour not_allowed)
				(footprints allowed)
			)
			(placement
				(enabled no)
				(sheetname "")
			)
			(fill
				(thermal_gap 0.5)
				(thermal_bridge_width 0.5)
				(island_removal_mode 0)
			)
			(polygon
				(pts
					(xy 156.6545 -139.6238) (xy 156.6545 -140.3858) (xy 156.1465 -140.3858) (xy 156.1465 -139.6238)
				)
			)
		)
	)
)
